# T6G (Grand Teton) — schematic netlist excerpt (pin names and nets, part order shuffled) for the footprints in the layout excerpt that follows; sources: Cadence DE-HDL packaged netlist, KiCad conversion of 04192023_DAF0TMB3IC0_F0TG_MB_C_brd_V02_OCP.brd

PC526_1  Q_CAP  22UF 4V 20% X6S  pkg C0805  page 225 : A = PVDD11_S3_P1 ; B = GND
R269  Q_RES  0 5% CHIP  pkg 0402LF  page 82 : A = CPU1_SP5R4 ; B = FM_CPU1_SP5R4
R6019  Q_RES  2K 5% EMPTY  pkg 0402LF  page 151 : A = P3V3_AUX ; B = SGPIO_SCM_LD_<0>

(kicad_pcb
	(version 20260206)
	(generator "pcbnew")
	(generator_version "10.0")
	(general
		(thickness 1.6)
		(legacy_teardrops no)
	)
	(paper "A4")
	(title_block
		(title "04192023_DAF0TMB3IC0_F0TG_MB_C_brd_V02_OCP.brd")
		(comment 1 "Grand Teton / footprints 8194-8196 of 8354")
	)
	(layers
		(0 "F.Cu" signal "TOP")
		(4 "In1.Cu" signal "GND")
		(6 "In2.Cu" signal "IN1")
		(8 "In3.Cu" signal "GND1")
		(10 "In4.Cu" signal "IN2")
		(12 "In5.Cu" signal "GND2")
		(14 "In6.Cu" signal "IN3")
		(16 "In7.Cu" signal "GND3")
		(18 "In8.Cu" signal "VCC")
		(20 "In9.Cu" signal "VCC1")
		(22 "In10.Cu" signal "GND4")
		(24 "In11.Cu" signal "IN4")
		(26 "In12.Cu" signal "GND5")
		(28 "In13.Cu" signal "IN5")
		(30 "In14.Cu" signal "GND6")
		(32 "In15.Cu" signal "IN6")
		(34 "In16.Cu" signal "GND7")
		(2 "B.Cu" signal "BOTTOM")
		(9 "F.Adhes" user "F.Adhesive")
		(11 "B.Adhes" user "B.Adhesive")
		(13 "F.Paste" user "Package Geometry/Pastemask Top")
		(15 "B.Paste" user "Package Geometry/Pastemask Bottom")
		(5 "F.SilkS" user "Ref Des/Silkscreen Top")
		(7 "B.SilkS" user "Ref Des/Silkscreen Bottom")
		(1 "F.Mask" user "Board Geometry/Soldermask Top")
		(3 "B.Mask" user "Board Geometry/Soldermask Bottom")
		(17 "Dwgs.User" user "User.Drawings")
		(19 "Cmts.User" user "User.Comments")
		(21 "Eco1.User" user "User.Eco1")
		(23 "Eco2.User" user "User.Eco2")
		(25 "Edge.Cuts" user "Board Geometry/Outline")
		(27 "Margin" user)
		(31 "F.CrtYd" user "Package Geometry/Place Bound Top")
		(29 "B.CrtYd" user "Package Geometry/Place Bound Bottom")
		(35 "F.Fab" user "Ref Des/Assembly Top")
		(33 "B.Fab" user "Ref Des/Assembly Bottom")
	)
	(footprint ""
		(layer "B.Cu")
		(at 190.881 -100.294948 -90)
		(property "Reference" "R269"
			(at 0 0 90)
			(layer "B.SilkS")
			(hide yes)
			(effects
				(font
					(size 1.27 1.27)
				)
				(justify mirror)
			)
		)
		(property "Value" ""
			(at 0 0 90)
			(layer "B.Fab")
			(effects
				(font
					(size 1.27 1.27)
				)
				(justify mirror)
			)
		)
		(duplicate_pad_numbers_are_jumpers no)
		(fp_line
			(start -0.7874 0.4064)
			(end 0.7874 0.4064)
			(stroke
				(width 0.1524)
				(type default)
			)
			(layer "B.SilkS")
		)
		(fp_line
			(start 0.7874 0.4064)
			(end 0.7874 -0.4064)
			(stroke
				(width 0.1524)
				(type default)
			)
			(layer "B.SilkS")
		)
		(fp_line
			(start -0.7874 -0.4064)
			(end -0.7874 0.4064)
			(stroke
				(width 0.1524)
				(type default)
			)
			(layer "B.SilkS")
		)
		(fp_line
			(start 0.7874 -0.4064)
			(end -0.7874 -0.4064)
			(stroke
				(width 0.1524)
				(type default)
			)
			(layer "B.SilkS")
		)
		(fp_line
			(start -0.67945 0.3048)
			(end -0.120396 0.3048)
			(stroke
				(width 0.1)
				(type default)
			)
			(layer "B.Fab")
		)
		(fp_line
			(start -0.120396 0.3048)
			(end -0.120396 0.2794)
			(stroke
				(width 0.1)
				(type default)
			)
			(layer "B.Fab")
		)
		(fp_line
			(start 0.12065 0.3048)
			(end 0.67945 0.3048)
			(stroke
				(width 0.1)
				(type default)
			)
			(layer "B.Fab")
		)
		(fp_line
			(start 0.67945 0.3048)
			(end 0.67945 -0.305054)
			(stroke
				(width 0.1)
				(type default)
			)
			(layer "B.Fab")
		)
		(fp_line
			(start -0.120396 0.2794)
			(end 0.12065 0.2794)
			(stroke
				(width 0.1)
				(type default)
			)
			(layer "B.Fab")
		)
		(fp_line
			(start 0.12065 0.2794)
			(end 0.12065 0.3048)
			(stroke
				(width 0.1)
				(type default)
			)
			(layer "B.Fab")
		)
		(fp_line
			(start -0.12065 -0.2794)
			(end -0.12065 -0.3048)
			(stroke
				(width 0.1)
				(type default)
			)
			(layer "B.Fab")
		)
		(fp_line
			(start 0.12065 -0.2794)
			(end -0.12065 -0.2794)
			(stroke
				(width 0.1)
				(type default)
			)
			(layer "B.Fab")
		)
		(fp_line
			(start -0.67945 -0.3048)
			(end -0.67945 0.3048)
			(stroke
				(width 0.1)
				(type default)
			)
			(layer "B.Fab")
		)
		(fp_line
			(start -0.12065 -0.3048)
			(end -0.67945 -0.3048)
			(stroke
				(width 0.1)
				(type default)
			)
			(layer "B.Fab")
		)
		(fp_line
			(start 0.12065 -0.305054)
			(end 0.12065 -0.2794)
			(stroke
				(width 0.1)
				(type default)
			)
			(layer "B.Fab")
		)
		(fp_line
			(start 0.67945 -0.305054)
			(end 0.12065 -0.305054)
			(stroke
				(width 0.1)
				(type default)
			)
			(layer "B.Fab")
		)
		(pad "1" smd circle
			(at 0.40005 0 90)
			(size 0 0)
			(layers "B.Cu" "B.Mask" "B.Paste")
			(net "CPU1_SP5R4")
		)
		(pad "2" smd circle
			(at -0.40005 0 90)
			(size 0 0)
			(layers "B.Cu" "B.Mask" "B.Paste")
			(net "FM_CPU1_SP5R4")
		)
	)
	(footprint ""
		(layer "B.Cu")
		(at 179.354734 -342.261952 -90)
		(property "Reference" "PC526_1"
			(at 0 0 90)
			(layer "B.SilkS")
			(hide yes)
			(effects
				(font
					(size 1.27 1.27)
				)
				(justify mirror)
			)
		)
		(property "Value" ""
			(at 0 0 90)
			(layer "B.Fab")
			(effects
				(font
					(size 1.27 1.27)
				)
				(justify mirror)
			)
		)
		(duplicate_pad_numbers_are_jumpers no)
		(fp_line
			(start -1.524 0.762)
			(end 1.524 0.762)
			(stroke
				(width 0.1524)
				(type default)
			)
			(layer "B.SilkS")
		)
		(fp_line
			(start 1.524 0.762)
			(end 1.524 -0.762)
			(stroke
				(width 0.1524)
				(type default)
			)
			(layer "B.SilkS")
		)
		(fp_line
			(start -1.524 -0.762)
			(end -1.524 0.762)
			(stroke
				(width 0.1524)
				(type default)
			)
			(layer "B.SilkS")
		)
		(fp_line
			(start 1.524 -0.762)
			(end -1.524 -0.762)
			(stroke
				(width 0.1524)
				(type default)
			)
			(layer "B.SilkS")
		)
		(fp_line
			(start -1.1049 0.724916)
			(end -1.1049 -0.724916)
			(stroke
				(width 0.1)
				(type default)
			)
			(layer "B.Fab")
		)
		(fp_line
			(start 1.1049 0.724916)
			(end -1.1049 0.724916)
			(stroke
				(width 0.1)
				(type default)
			)
			(layer "B.Fab")
		)
		(fp_line
			(start -1.1049 -0.724916)
			(end 1.1049 -0.724916)
			(stroke
				(width 0.1)
				(type default)
			)
			(layer "B.Fab")
		)
		(fp_line
			(start 1.1049 -0.724916)
			(end 1.1049 0.724916)
			(stroke
				(width 0.1)
				(type default)
			)
			(layer "B.Fab")
		)
		(pad "1" smd rect
			(at 0.889 0 270)
			(size 1.016 1.27)
			(layers "B.Cu" "B.Mask" "B.Paste")
			(net "PVDD11_S3_P1")
		)
		(pad "2" smd rect
			(at -0.889 0 270)
			(size 1.016 1.27)
			(layers "B.Cu" "B.Mask" "B.Paste")
			(net "GND")
		)
	)
	(footprint ""
		(layer "B.Cu")
		(at 171.577 -100.294948 -90)
		(property "Reference" "R6019"
			(at 0 0 90)
			(layer "B.SilkS")
			(hide yes)
			(effects
				(font
					(size 1.27 1.27)
				)
				(justify mirror)
			)
		)
		(property "Value" ""
			(at 0 0 90)
			(layer "B.Fab")
			(effects
				(font
					(size 1.27 1.27)
				)
				(justify mirror)
			)
		)
		(duplicate_pad_numbers_are_jumpers no)
		(fp_line
			(start -0.7874 0.4064)
			(end 0.7874 0.4064)
			(stroke
				(width 0.1524)
				(type default)
			)
			(layer "B.SilkS")
		)
		(fp_line
			(start 0.7874 0.4064)
			(end 0.7874 -0.4064)
			(stroke
				(width 0.1524)
				(type default)
			)
			(layer "B.SilkS")
		)
		(fp_line
			(start -0.7874 -0.4064)
			(end -0.7874 0.4064)
			(stroke
				(width 0.1524)
				(type default)
			)
			(layer "B.SilkS")
		)
		(fp_line
			(start 0.7874 -0.4064)
			(end -0.7874 -0.4064)
			(stroke
				(width 0.1524)
				(type default)
			)
			(layer "B.SilkS")
		)
		(fp_line
			(start -0.67945 0.3048)
			(end -0.120396 0.3048)
			(stroke
				(width 0.1)
				(type default)
			)
			(layer "B.Fab")
		)
		(fp_line
			(start -0.120396 0.3048)
			(end -0.120396 0.2794)
			(stroke
				(width 0.1)
				(type default)
			)
			(layer "B.Fab")
		)
		(fp_line
			(start 0.12065 0.3048)
			(end 0.67945 0.3048)
			(stroke
				(width 0.1)
				(type default)
			)
			(layer "B.Fab")
		)
		(fp_line
			(start 0.67945 0.3048)
			(end 0.67945 -0.305054)
			(stroke
				(width 0.1)
				(type default)
			)
			(layer "B.Fab")
		)
		(fp_line
			(start -0.120396 0.2794)
			(end 0.12065 0.2794)
			(stroke
				(width 0.1)
				(type default)
			)
			(layer "B.Fab")
		)
		(fp_line
			(start 0.12065 0.2794)
			(end 0.12065 0.3048)
			(stroke
				(width 0.1)
				(type default)
			)
			(layer "B.Fab")
		)
		(fp_line
			(start -0.12065 -0.2794)
			(end -0.12065 -0.3048)
			(stroke
				(width 0.1)
				(type default)
			)
			(layer "B.Fab")
		)
		(fp_line
			(start 0.12065 -0.2794)
			(end -0.12065 -0.2794)
			(stroke
				(width 0.1)
				(type default)
			)
			(layer "B.Fab")
		)
		(fp_line
			(start -0.67945 -0.3048)
			(end -0.67945 0.3048)
			(stroke
				(width 0.1)
				(type default)
			)
			(layer "B.Fab")
		)
		(fp_line
			(start -0.12065 -0.3048)
			(end -0.67945 -0.3048)
			(stroke
				(width 0.1)
				(type default)
			)
			(layer "B.Fab")
		)
		(fp_line
			(start 0.12065 -0.305054)
			(end 0.12065 -0.2794)
			(stroke
				(width 0.1)
				(type default)
			)
			(layer "B.Fab")
		)
		(fp_line
			(start 0.67945 -0.305054)
			(end 0.12065 -0.305054)
			(stroke
				(width 0.1)
				(type default)
			)
			(layer "B.Fab")
		)
		(pad "1" smd circle
			(at 0.40005 0 90)
			(size 0 0)
			(layers "B.Cu" "B.Mask" "B.Paste")
			(net "P3V3_AUX")
		)
		(pad "2" smd circle
			(at -0.40005 0 90)
			(size 0 0)
			(layers "B.Cu" "B.Mask" "B.Paste")
			(net "SGPIO_SCM_LD_<0>")
		)
	)
)
